# T6G (Grand Teton) — schematic netlist excerpt (pin names and nets, part order shuffled) for the footprints in the layout excerpt that follows; sources: Cadence DE-HDL packaged netlist, KiCad conversion of 04192023_DAF0TMB3IC0_F0TG_MB_C_brd_V02_OCP.brd

R4475  Q_RES  1 1% CHIP  pkg 0603LF  page 182 : A = P3V3_9ZXL045_P0 ; B = P3V3_9ZXL045_P0_VDDR
R760  Q_RES  10K 5% CHIP  pkg 0402LF  page 76 : A = GND ; B = PD_ESPI_CPU1_CLK2

(kicad_pcb
	(version 20260206)
	(generator "pcbnew")
	(generator_version "10.0")
	(general
		(thickness 1.6)
		(legacy_teardrops no)
	)
	(paper "A4")
	(title_block
		(title "04192023_DAF0TMB3IC0_F0TG_MB_C_brd_V02_OCP.brd")
		(comment 1 "Grand Teton / footprints 1785-1786 of 8354")
	)
	(layers
		(0 "F.Cu" signal "TOP")
		(4 "In1.Cu" signal "GND")
		(6 "In2.Cu" signal "IN1")
		(8 "In3.Cu" signal "GND1")
		(10 "In4.Cu" signal "IN2")
		(12 "In5.Cu" signal "GND2")
		(14 "In6.Cu" signal "IN3")
		(16 "In7.Cu" signal "GND3")
		(18 "In8.Cu" signal "VCC")
		(20 "In9.Cu" signal "VCC1")
		(22 "In10.Cu" signal "GND4")
		(24 "In11.Cu" signal "IN4")
		(26 "In12.Cu" signal "GND5")
		(28 "In13.Cu" signal "IN5")
		(30 "In14.Cu" signal "GND6")
		(32 "In15.Cu" signal "IN6")
		(34 "In16.Cu" signal "GND7")
		(2 "B.Cu" signal "BOTTOM")
		(9 "F.Adhes" user "F.Adhesive")
		(11 "B.Adhes" user "B.Adhesive")
		(13 "F.Paste" user "Package Geometry/Pastemask Top")
		(15 "B.Paste" user "Package Geometry/Pastemask Bottom")
		(5 "F.SilkS" user "Ref Des/Silkscreen Top")
		(7 "B.SilkS" user "Ref Des/Silkscreen Bottom")
		(1 "F.Mask" user "Board Geometry/Soldermask Top")
		(3 "B.Mask" user "Board Geometry/Soldermask Bottom")
		(17 "Dwgs.User" user "User.Drawings")
		(19 "Cmts.User" user "User.Comments")
		(21 "Eco1.User" user "User.Eco1")
		(23 "Eco2.User" user "User.Eco2")
		(25 "Edge.Cuts" user "Board Geometry/Outline")
		(27 "Margin" user)
		(31 "F.CrtYd" user "Package Geometry/Place Bound Top")
		(29 "B.CrtYd" user "Package Geometry/Place Bound Bottom")
		(35 "F.Fab" user "Ref Des/Assembly Top")
		(33 "B.Fab" user "Ref Des/Assembly Bottom")
	)
	(footprint ""
		(layer "F.Cu")
		(at 281.94 -426.212 -90)
		(property "Reference" "R4475"
			(at 0 0 270)
			(layer "F.SilkS")
			(hide yes)
			(effects
				(font
					(size 1.27 1.27)
				)
			)
		)
		(property "Value" ""
			(at 0 0 270)
			(layer "F.Fab")
			(effects
				(font
					(size 1.27 1.27)
				)
			)
		)
		(duplicate_pad_numbers_are_jumpers no)
		(fp_line
			(start -1.2954 0.5842)
			(end -1.2954 -0.5842)
			(stroke
				(width 0.1524)
				(type default)
			)
			(layer "F.SilkS")
		)
		(fp_line
			(start 1.2954 0.5842)
			(end -1.2954 0.5842)
			(stroke
				(width 0.1524)
				(type default)
			)
			(layer "F.SilkS")
		)
		(fp_line
			(start -1.2954 -0.5842)
			(end 1.2954 -0.5842)
			(stroke
				(width 0.1524)
				(type default)
			)
			(layer "F.SilkS")
		)
		(fp_line
			(start 1.2954 -0.5842)
			(end 1.2954 0.5842)
			(stroke
				(width 0.1524)
				(type default)
			)
			(layer "F.SilkS")
		)
		(fp_line
			(start -0.8636 0.4572)
			(end -0.8636 0.4318)
			(stroke
				(width 0.1)
				(type default)
			)
			(layer "F.Fab")
		)
		(fp_line
			(start 0.8636 0.4572)
			(end -0.8636 0.4572)
			(stroke
				(width 0.1)
				(type default)
			)
			(layer "F.Fab")
		)
		(fp_line
			(start -0.8636 0.4318)
			(end -0.8636 0.4064)
			(stroke
				(width 0.1)
				(type default)
			)
			(layer "F.Fab")
		)
		(fp_line
			(start -1.1938 0.4064)
			(end -1.1938 -0.406654)
			(stroke
				(width 0.1)
				(type default)
			)
			(layer "F.Fab")
		)
		(fp_line
			(start -0.8636 0.4064)
			(end -1.1938 0.4064)
			(stroke
				(width 0.1)
				(type default)
			)
			(layer "F.Fab")
		)
		(fp_line
			(start 0.8636 0.4064)
			(end 0.8636 0.4572)
			(stroke
				(width 0.1)
				(type default)
			)
			(layer "F.Fab")
		)
		(fp_line
			(start 1.1938 0.4064)
			(end 0.8636 0.4064)
			(stroke
				(width 0.1)
				(type default)
			)
			(layer "F.Fab")
		)
		(fp_line
			(start -1.1938 -0.406654)
			(end -0.8636 -0.406654)
			(stroke
				(width 0.1)
				(type default)
			)
			(layer "F.Fab")
		)
		(fp_line
			(start -0.8636 -0.406654)
			(end -0.8636 -0.4572)
			(stroke
				(width 0.1)
				(type default)
			)
			(layer "F.Fab")
		)
		(fp_line
			(start 0.8636 -0.406654)
			(end 1.1938 -0.406654)
			(stroke
				(width 0.1)
				(type default)
			)
			(layer "F.Fab")
		)
		(fp_line
			(start 1.1938 -0.406654)
			(end 1.1938 0.4064)
			(stroke
				(width 0.1)
				(type default)
			)
			(layer "F.Fab")
		)
		(fp_line
			(start -0.8636 -0.4572)
			(end 0.8636 -0.4572)
			(stroke
				(width 0.1)
				(type default)
			)
			(layer "F.Fab")
		)
		(fp_line
			(start 0.8636 -0.4572)
			(end 0.8636 -0.406654)
			(stroke
				(width 0.1)
				(type default)
			)
			(layer "F.Fab")
		)
		(pad "1" smd rect
			(at -0.7366 0 180)
			(size 0.7112 0.8128)
			(layers "F.Cu" "F.Mask" "F.Paste")
			(net "P3V3_9ZXL045_P0")
		)
		(pad "2" smd rect
			(at 0.7366 0 180)
			(size 0.7112 0.8128)
			(layers "F.Cu" "F.Mask" "F.Paste")
			(net "P3V3_9ZXL045_P0_VDDR")
		)
	)
	(footprint ""
		(layer "F.Cu")
		(at 152.849834 -323.747892 180)
		(property "Reference" "R760"
			(at 0 0 180)
			(layer "F.SilkS")
			(hide yes)
			(effects
				(font
					(size 1.27 1.27)
				)
			)
		)
		(property "Value" ""
			(at 0 0 180)
			(layer "F.Fab")
			(effects
				(font
					(size 1.27 1.27)
				)
			)
		)
		(duplicate_pad_numbers_are_jumpers no)
		(fp_line
			(start 0.7874 0.4064)
			(end -0.7874 0.4064)
			(stroke
				(width 0.1524)
				(type default)
			)
			(layer "F.SilkS")
		)
		(fp_line
			(start 0.7874 -0.4064)
			(end 0.7874 0.4064)
			(stroke
				(width 0.1524)
				(type default)
			)
			(layer "F.SilkS")
		)
		(fp_line
			(start -0.7874 0.4064)
			(end -0.7874 -0.4064)
			(stroke
				(width 0.1524)
				(type default)
			)
			(layer "F.SilkS")
		)
		(fp_line
			(start -0.7874 -0.4064)
			(end 0.7874 -0.4064)
			(stroke
				(width 0.1524)
				(type default)
			)
			(layer "F.SilkS")
		)
		(fp_line
			(start 0.67945 0.3048)
			(end 0.120396 0.3048)
			(stroke
				(width 0.1)
				(type default)
			)
			(layer "F.Fab")
		)
		(fp_line
			(start 0.67945 -0.3048)
			(end 0.67945 0.3048)
			(stroke
				(width 0.1)
				(type default)
			)
			(layer "F.Fab")
		)
		(fp_line
			(start 0.12065 -0.2794)
			(end 0.12065 -0.3048)
			(stroke
				(width 0.1)
				(type default)
			)
			(layer "F.Fab")
		)
		(fp_line
			(start 0.12065 -0.3048)
			(end 0.67945 -0.3048)
			(stroke
				(width 0.1)
				(type default)
			)
			(layer "F.Fab")
		)
		(fp_line
			(start 0.120396 0.3048)
			(end 0.120396 0.2794)
			(stroke
				(width 0.1)
				(type default)
			)
			(layer "F.Fab")
		)
		(fp_line
			(start 0.120396 0.2794)
			(end -0.12065 0.2794)
			(stroke
				(width 0.1)
				(type default)
			)
			(layer "F.Fab")
		)
		(fp_line
			(start -0.12065 0.3048)
			(end -0.67945 0.3048)
			(stroke
				(width 0.1)
				(type default)
			)
			(layer "F.Fab")
		)
		(fp_line
			(start -0.12065 0.2794)
			(end -0.12065 0.3048)
			(stroke
				(width 0.1)
				(type default)
			)
			(layer "F.Fab")
		)
		(fp_line
			(start -0.12065 -0.2794)
			(end 0.12065 -0.2794)
			(stroke
				(width 0.1)
				(type default)
			)
			(layer "F.Fab")
		)
		(fp_line
			(start -0.12065 -0.305054)
			(end -0.12065 -0.2794)
			(stroke
				(width 0.1)
				(type default)
			)
			(layer "F.Fab")
		)
		(fp_line
			(start -0.67945 0.3048)
			(end -0.67945 -0.305054)
			(stroke
				(width 0.1)
				(type default)
			)
			(layer "F.Fab")
		)
		(fp_line
			(start -0.67945 -0.305054)
			(end -0.12065 -0.305054)
			(stroke
				(width 0.1)
				(type default)
			)
			(layer "F.Fab")
		)
		(pad "1" smd circle
			(at -0.40005 0 180)
			(size 0 0)
			(layers "F.Cu" "F.Mask" "F.Paste")
			(net "GND")
		)
		(pad "2" smd circle
			(at 0.40005 0 180)
			(size 0 0)
			(layers "F.Cu" "F.Mask" "F.Paste")
			(net "PD_ESPI_CPU1_CLK2")
		)
	)
)
